(kicad_pcb
	(version 20260206)
	(generator "pcbnew")
	(generator_version "10.0")
	(general
		(thickness 1.6)
		(legacy_teardrops no)
	)
	(paper "A4")
	(title_block
		(title "04192023_DAF0TMB3IC0_F0TG_MB_C_brd_V02_OCP.brd")
		(comment 1 "Grand Teton / footprints 6932-6939 of 8354")
	)
	(layers
		(0 "F.Cu" signal "TOP")
		(4 "In1.Cu" signal "GND")
		(6 "In2.Cu" signal "IN1")
		(8 "In3.Cu" signal "GND1")
		(10 "In4.Cu" signal "IN2")
		(12 "In5.Cu" signal "GND2")
		(14 "In6.Cu" signal "IN3")
		(16 "In7.Cu" signal "GND3")
		(18 "In8.Cu" signal "VCC")
		(20 "In9.Cu" signal "VCC1")
		(22 "In10.Cu" signal "GND4")
		(24 "In11.Cu" signal "IN4")
		(26 "In12.Cu" signal "GND5")
		(28 "In13.Cu" signal "IN5")
		(30 "In14.Cu" signal "GND6")
		(32 "In15.Cu" signal "IN6")
		(34 "In16.Cu" signal "GND7")
		(2 "B.Cu" signal "BOTTOM")
		(9 "F.Adhes" user "F.Adhesive")
		(11 "B.Adhes" user "B.Adhesive")
		(13 "F.Paste" user "Package Geometry/Pastemask Top")
		(15 "B.Paste" user "Package Geometry/Pastemask Bottom")
		(5 "F.SilkS" user "Ref Des/Silkscreen Top")
		(7 "B.SilkS" user "Ref Des/Silkscreen Bottom")
		(1 "F.Mask" user "Board Geometry/Soldermask Top")
		(3 "B.Mask" user "Board Geometry/Soldermask Bottom")
		(17 "Dwgs.User" user "User.Drawings")
		(19 "Cmts.User" user "User.Comments")
		(21 "Eco1.User" user "User.Eco1")
		(23 "Eco2.User" user "User.Eco2")
		(25 "Edge.Cuts" user "Board Geometry/Outline")
		(27 "Margin" user)
		(31 "F.CrtYd" user "Package Geometry/Place Bound Top")
		(29 "B.CrtYd" user "Package Geometry/Place Bound Bottom")
		(35 "F.Fab" user "Ref Des/Assembly Top")
		(33 "B.Fab" user "Ref Des/Assembly Bottom")
	)
	(footprint ""
		(layer "B.Cu")
		(at 73.889616 -393.242546 180)
		(property "Reference" "R712"
			(at 0 0 0)
			(layer "B.SilkS")
			(hide yes)
			(effects
				(font
					(size 1.27 1.27)
				)
				(justify mirror)
			)
		)
		(property "Value" ""
			(at 0 0 0)
			(layer "B.Fab")
			(effects
				(font
					(size 1.27 1.27)
				)
				(justify mirror)
			)
		)
		(duplicate_pad_numbers_are_jumpers no)
		(fp_line
			(start 1.2954 0.5842)
			(end 1.2954 -0.5842)
			(stroke
				(width 0.1524)
				(type default)
			)
			(layer "B.SilkS")
		)
		(fp_line
			(start 1.2954 -0.5842)
			(end -1.2954 -0.5842)
			(stroke
				(width 0.1524)
				(type default)
			)
			(layer "B.SilkS")
		)
		(fp_line
			(start -1.2954 0.5842)
			(end 1.2954 0.5842)
			(stroke
				(width 0.1524)
				(type default)
			)
			(layer "B.SilkS")
		)
		(fp_line
			(start -1.2954 -0.5842)
			(end -1.2954 0.5842)
			(stroke
				(width 0.1524)
				(type default)
			)
			(layer "B.SilkS")
		)
		(fp_line
			(start 1.1938 0.4064)
			(end 1.1938 -0.406654)
			(stroke
				(width 0.1)
				(type default)
			)
			(layer "B.Fab")
		)
		(fp_line
			(start 1.1938 -0.406654)
			(end 0.8636 -0.406654)
			(stroke
				(width 0.1)
				(type default)
			)
			(layer "B.Fab")
		)
		(fp_line
			(start 0.8636 0.4572)
			(end 0.8636 0.4318)
			(stroke
				(width 0.1)
				(type default)
			)
			(layer "B.Fab")
		)
		(fp_line
			(start 0.8636 0.4318)
			(end 0.8636 0.4064)
			(stroke
				(width 0.1)
				(type default)
			)
			(layer "B.Fab")
		)
		(fp_line
			(start 0.8636 0.4064)
			(end 1.1938 0.4064)
			(stroke
				(width 0.1)
				(type default)
			)
			(layer "B.Fab")
		)
		(fp_line
			(start 0.8636 -0.406654)
			(end 0.8636 -0.4572)
			(stroke
				(width 0.1)
				(type default)
			)
			(layer "B.Fab")
		)
		(fp_line
			(start 0.8636 -0.4572)
			(end -0.8636 -0.4572)
			(stroke
				(width 0.1)
				(type default)
			)
			(layer "B.Fab")
		)
		(fp_line
			(start -0.8636 0.4572)
			(end 0.8636 0.4572)
			(stroke
				(width 0.1)
				(type default)
			)
			(layer "B.Fab")
		)
		(fp_line
			(start -0.8636 0.4064)
			(end -0.8636 0.4572)
			(stroke
				(width 0.1)
				(type default)
			)
			(layer "B.Fab")
		)
		(fp_line
			(start -0.8636 -0.406654)
			(end -1.1938 -0.406654)
			(stroke
				(width 0.1)
				(type default)
			)
			(layer "B.Fab")
		)
		(fp_line
			(start -0.8636 -0.4572)
			(end -0.8636 -0.406654)
			(stroke
				(width 0.1)
				(type default)
			)
			(layer "B.Fab")
		)
		(fp_line
			(start -1.1938 0.4064)
			(end -0.8636 0.4064)
			(stroke
				(width 0.1)
				(type default)
			)
			(layer "B.Fab")
		)
		(fp_line
			(start -1.1938 -0.406654)
			(end -1.1938 0.4064)
			(stroke
				(width 0.1)
				(type default)
			)
			(layer "B.Fab")
		)
		(pad "1" smd rect
			(at 0.7366 0 90)
			(size 0.7112 0.8128)
			(layers "B.Cu" "B.Mask" "B.Paste")
			(net "P0V9_CPU1_RT1_2A_2D")
		)
		(pad "2" smd rect
			(at -0.7366 0 90)
			(size 0.7112 0.8128)
			(layers "B.Cu" "B.Mask" "B.Paste")
			(net "P0V9_CPU1_RT1_2A")
		)
	)
	(footprint ""
		(layer "B.Cu")
		(at 293.12997 -346.784168 90)
		(property "Reference" "PC153_2"
			(at 0 0 90)
			(layer "B.SilkS")
			(hide yes)
			(effects
				(font
					(size 1.27 1.27)
				)
				(justify mirror)
			)
		)
		(property "Value" ""
			(at 0 0 90)
			(layer "B.Fab")
			(effects
				(font
					(size 1.27 1.27)
				)
				(justify mirror)
			)
		)
		(duplicate_pad_numbers_are_jumpers no)
		(fp_line
			(start 1.524 -0.762)
			(end -1.524 -0.762)
			(stroke
				(width 0.1524)
				(type default)
			)
			(layer "B.SilkS")
		)
		(fp_line
			(start -1.524 -0.762)
			(end -1.524 0.762)
			(stroke
				(width 0.1524)
				(type default)
			)
			(layer "B.SilkS")
		)
		(fp_line
			(start 1.524 0.762)
			(end 1.524 -0.762)
			(stroke
				(width 0.1524)
				(type default)
			)
			(layer "B.SilkS")
		)
		(fp_line
			(start -1.524 0.762)
			(end 1.524 0.762)
			(stroke
				(width 0.1524)
				(type default)
			)
			(layer "B.SilkS")
		)
		(fp_line
			(start 1.1049 -0.724916)
			(end 1.1049 0.724916)
			(stroke
				(width 0.1)
				(type default)
			)
			(layer "B.Fab")
		)
		(fp_line
			(start -1.1049 -0.724916)
			(end 1.1049 -0.724916)
			(stroke
				(width 0.1)
				(type default)
			)
			(layer "B.Fab")
		)
		(fp_line
			(start 1.1049 0.724916)
			(end -1.1049 0.724916)
			(stroke
				(width 0.1)
				(type default)
			)
			(layer "B.Fab")
		)
		(fp_line
			(start -1.1049 0.724916)
			(end -1.1049 -0.724916)
			(stroke
				(width 0.1)
				(type default)
			)
			(layer "B.Fab")
		)
		(pad "1" smd rect
			(at 0.889 0 90)
			(size 1.016 1.27)
			(layers "B.Cu" "B.Mask" "B.Paste")
			(net "SW_P12V_AUX_PVDDIO_P0_FLT")
		)
		(pad "2" smd rect
			(at -0.889 0 90)
			(size 1.016 1.27)
			(layers "B.Cu" "B.Mask" "B.Paste")
			(net "GND")
		)
	)
	(footprint ""
		(layer "B.Cu")
		(at 119.621554 -177.007012 90)
		(property "Reference" "PC344_1"
			(at 0 0 90)
			(layer "B.SilkS")
			(hide yes)
			(effects
				(font
					(size 1.27 1.27)
				)
				(justify mirror)
			)
		)
		(property "Value" ""
			(at 0 0 90)
			(layer "B.Fab")
			(effects
				(font
					(size 1.27 1.27)
				)
				(justify mirror)
			)
		)
		(duplicate_pad_numbers_are_jumpers no)
		(fp_line
			(start 1.524 -0.762)
			(end -1.524 -0.762)
			(stroke
				(width 0.1524)
				(type default)
			)
			(layer "B.SilkS")
		)
		(fp_line
			(start -1.524 -0.762)
			(end -1.524 0.762)
			(stroke
				(width 0.1524)
				(type default)
			)
			(layer "B.SilkS")
		)
		(fp_line
			(start 1.524 0.762)
			(end 1.524 -0.762)
			(stroke
				(width 0.1524)
				(type default)
			)
			(layer "B.SilkS")
		)
		(fp_line
			(start -1.524 0.762)
			(end 1.524 0.762)
			(stroke
				(width 0.1524)
				(type default)
			)
			(layer "B.SilkS")
		)
		(fp_line
			(start 1.1049 -0.724916)
			(end 1.1049 0.724916)
			(stroke
				(width 0.1)
				(type default)
			)
			(layer "B.Fab")
		)
		(fp_line
			(start -1.1049 -0.724916)
			(end 1.1049 -0.724916)
			(stroke
				(width 0.1)
				(type default)
			)
			(layer "B.Fab")
		)
		(fp_line
			(start 1.1049 0.724916)
			(end -1.1049 0.724916)
			(stroke
				(width 0.1)
				(type default)
			)
			(layer "B.Fab")
		)
		(fp_line
			(start -1.1049 0.724916)
			(end -1.1049 -0.724916)
			(stroke
				(width 0.1)
				(type default)
			)
			(layer "B.Fab")
		)
		(pad "1" smd rect
			(at 0.889 0 90)
			(size 1.016 1.27)
			(layers "B.Cu" "B.Mask" "B.Paste")
			(net "PVDDCR_SOC_P1")
		)
		(pad "2" smd rect
			(at -0.889 0 90)
			(size 1.016 1.27)
			(layers "B.Cu" "B.Mask" "B.Paste")
			(net "GND")
		)
	)
	(footprint ""
		(layer "B.Cu")
		(at 75.7936 -385.58216 180)
		(property "Reference" "R785"
			(at 0 0 0)
			(layer "B.SilkS")
			(hide yes)
			(effects
				(font
					(size 1.27 1.27)
				)
				(justify mirror)
			)
		)
		(property "Value" ""
			(at 0 0 0)
			(layer "B.Fab")
			(effects
				(font
					(size 1.27 1.27)
				)
				(justify mirror)
			)
		)
		(duplicate_pad_numbers_are_jumpers no)
		(fp_line
			(start 0.32512 0.175006)
			(end 0.32512 -0.175006)
			(stroke
				(width 0.1)
				(type default)
			)
			(layer "B.Fab")
		)
		(fp_line
			(start 0.32512 -0.175006)
			(end -0.32512 -0.175006)
			(stroke
				(width 0.1)
				(type default)
			)
			(layer "B.Fab")
		)
		(fp_line
			(start -0.32512 0.175006)
			(end 0.32512 0.175006)
			(stroke
				(width 0.1)
				(type default)
			)
			(layer "B.Fab")
		)
		(fp_line
			(start -0.32512 -0.175006)
			(end -0.32512 0.175006)
			(stroke
				(width 0.1)
				(type default)
			)
			(layer "B.Fab")
		)
		(pad "1" smd rect
			(at 0.2667 0)
			(size 0.3048 0.381)
			(layers "B.Cu" "B.Mask" "B.Paste")
			(net "TEST0_RT_CPU1_P1")
		)
		(pad "2" smd rect
			(at -0.2667 0 180)
			(size 0.3048 0.381)
			(layers "B.Cu" "B.Mask" "B.Paste")
			(net "GND")
		)
	)
	(footprint ""
		(layer "B.Cu")
		(at 315.378338 -395.148562 90)
		(property "Reference" "C578"
			(at 0 0 90)
			(layer "B.SilkS")
			(hide yes)
			(effects
				(font
					(size 1.27 1.27)
				)
				(justify mirror)
			)
		)
		(property "Value" ""
			(at 0 0 90)
			(layer "B.Fab")
			(effects
				(font
					(size 1.27 1.27)
				)
				(justify mirror)
			)
		)
		(duplicate_pad_numbers_are_jumpers no)
		(fp_line
			(start 0.299974 -0.150114)
			(end -0.299974 -0.150114)
			(stroke
				(width 0.1)
				(type default)
			)
			(layer "B.Fab")
		)
		(fp_line
			(start -0.299974 -0.150114)
			(end -0.299974 0.150114)
			(stroke
				(width 0.1)
				(type default)
			)
			(layer "B.Fab")
		)
		(fp_line
			(start 0.299974 0.150114)
			(end 0.299974 -0.150114)
			(stroke
				(width 0.1)
				(type default)
			)
			(layer "B.Fab")
		)
		(fp_line
			(start -0.299974 0.150114)
			(end 0.299974 0.150114)
			(stroke
				(width 0.1)
				(type default)
			)
			(layer "B.Fab")
		)
		(pad "1" smd rect
			(at 0.2667 0 270)
			(size 0.3048 0.381)
			(layers "B.Cu" "B.Mask" "B.Paste")
			(net "P0V9_CPU0_RT_2D")
		)
		(pad "2" smd rect
			(at -0.2667 0 270)
			(size 0.3048 0.381)
			(layers "B.Cu" "B.Mask" "B.Paste")
			(net "GND")
		)
	)
	(footprint ""
		(layer "B.Cu")
		(at 94.435422 -60.820808)
		(property "Reference" "R3807"
			(at 0 0 0)
			(layer "B.SilkS")
			(hide yes)
			(effects
				(font
					(size 1.27 1.27)
				)
				(justify mirror)
			)
		)
		(property "Value" ""
			(at 0 0 0)
			(layer "B.Fab")
			(effects
				(font
					(size 1.27 1.27)
				)
				(justify mirror)
			)
		)
		(duplicate_pad_numbers_are_jumpers no)
		(fp_line
			(start -0.7874 -0.4064)
			(end -0.7874 0.4064)
			(stroke
				(width 0.1524)
				(type default)
			)
			(layer "B.SilkS")
		)
		(fp_line
			(start -0.7874 0.4064)
			(end 0.7874 0.4064)
			(stroke
				(width 0.1524)
				(type default)
			)
			(layer "B.SilkS")
		)
		(fp_line
			(start 0.7874 -0.4064)
			(end -0.7874 -0.4064)
			(stroke
				(width 0.1524)
				(type default)
			)
			(layer "B.SilkS")
		)
		(fp_line
			(start 0.7874 0.4064)
			(end 0.7874 -0.4064)
			(stroke
				(width 0.1524)
				(type default)
			)
			(layer "B.SilkS")
		)
		(fp_line
			(start -0.67945 -0.3048)
			(end -0.67945 0.3048)
			(stroke
				(width 0.1)
				(type default)
			)
			(layer "B.Fab")
		)
		(fp_line
			(start -0.67945 0.3048)
			(end -0.120396 0.3048)
			(stroke
				(width 0.1)
				(type default)
			)
			(layer "B.Fab")
		)
		(fp_line
			(start -0.12065 -0.3048)
			(end -0.67945 -0.3048)
			(stroke
				(width 0.1)
				(type default)
			)
			(layer "B.Fab")
		)
		(fp_line
			(start -0.12065 -0.2794)
			(end -0.12065 -0.3048)
			(stroke
				(width 0.1)
				(type default)
			)
			(layer "B.Fab")
		)
		(fp_line
			(start -0.120396 0.2794)
			(end 0.12065 0.2794)
			(stroke
				(width 0.1)
				(type default)
			)
			(layer "B.Fab")
		)
		(fp_line
			(start -0.120396 0.3048)
			(end -0.120396 0.2794)
			(stroke
				(width 0.1)
				(type default)
			)
			(layer "B.Fab")
		)
		(fp_line
			(start 0.12065 -0.305054)
			(end 0.12065 -0.2794)
			(stroke
				(width 0.1)
				(type default)
			)
			(layer "B.Fab")
		)
		(fp_line
			(start 0.12065 -0.2794)
			(end -0.12065 -0.2794)
			(stroke
				(width 0.1)
				(type default)
			)
			(layer "B.Fab")
		)
		(fp_line
			(start 0.12065 0.2794)
			(end 0.12065 0.3048)
			(stroke
				(width 0.1)
				(type default)
			)
			(layer "B.Fab")
		)
		(fp_line
			(start 0.12065 0.3048)
			(end 0.67945 0.3048)
			(stroke
				(width 0.1)
				(type default)
			)
			(layer "B.Fab")
		)
		(fp_line
			(start 0.67945 -0.305054)
			(end 0.12065 -0.305054)
			(stroke
				(width 0.1)
				(type default)
			)
			(layer "B.Fab")
		)
		(fp_line
			(start 0.67945 0.3048)
			(end 0.67945 -0.305054)
			(stroke
				(width 0.1)
				(type default)
			)
			(layer "B.Fab")
		)
		(pad "1" smd circle
			(at 0.40005 0 180)
			(size 0 0)
			(layers "B.Cu" "B.Mask" "B.Paste")
			(net "P3V3_OCP_UV_2_R1")
		)
		(pad "2" smd circle
			(at -0.40005 0 180)
			(size 0 0)
			(layers "B.Cu" "B.Mask" "B.Paste")
			(net "P3V3_OCP_UV_2")
		)
	)
	(footprint ""
		(layer "B.Cu")
		(at 125.895608 -38.87343 90)
		(property "Reference" "C6061"
			(at 0 0 90)
			(layer "B.SilkS")
			(hide yes)
			(effects
				(font
					(size 1.27 1.27)
				)
				(justify mirror)
			)
		)
		(property "Value" ""
			(at 0 0 90)
			(layer "B.Fab")
			(effects
				(font
					(size 1.27 1.27)
				)
				(justify mirror)
			)
		)
		(duplicate_pad_numbers_are_jumpers no)
		(fp_line
			(start 0.7874 -0.4064)
			(end -0.7874 -0.4064)
			(stroke
				(width 0.1524)
				(type default)
			)
			(layer "B.SilkS")
		)
		(fp_line
			(start -0.7874 -0.4064)
			(end -0.7874 0.4064)
			(stroke
				(width 0.1524)
				(type default)
			)
			(layer "B.SilkS")
		)
		(fp_line
			(start 0.7874 0.4064)
			(end 0.7874 -0.4064)
			(stroke
				(width 0.1524)
				(type default)
			)
			(layer "B.SilkS")
		)
		(fp_line
			(start -0.7874 0.4064)
			(end 0.7874 0.4064)
			(stroke
				(width 0.1524)
				(type default)
			)
			(layer "B.SilkS")
		)
		(fp_line
			(start 0.67945 -0.305054)
			(end 0.12065 -0.305054)
			(stroke
				(width 0.1)
				(type default)
			)
			(layer "B.Fab")
		)
		(fp_line
			(start 0.12065 -0.305054)
			(end 0.12065 -0.2794)
			(stroke
				(width 0.1)
				(type default)
			)
			(layer "B.Fab")
		)
		(fp_line
			(start -0.12065 -0.3048)
			(end -0.67945 -0.3048)
			(stroke
				(width 0.1)
				(type default)
			)
			(layer "B.Fab")
		)
		(fp_line
			(start -0.67945 -0.3048)
			(end -0.67945 0.3048)
			(stroke
				(width 0.1)
				(type default)
			)
			(layer "B.Fab")
		)
		(fp_line
			(start 0.12065 -0.2794)
			(end -0.12065 -0.2794)
			(stroke
				(width 0.1)
				(type default)
			)
			(layer "B.Fab")
		)
		(fp_line
			(start -0.12065 -0.2794)
			(end -0.12065 -0.3048)
			(stroke
				(width 0.1)
				(type default)
			)
			(layer "B.Fab")
		)
		(fp_line
			(start 0.12065 0.2794)
			(end 0.12065 0.3048)
			(stroke
				(width 0.1)
				(type default)
			)
			(layer "B.Fab")
		)
		(fp_line
			(start -0.120396 0.2794)
			(end 0.12065 0.2794)
			(stroke
				(width 0.1)
				(type default)
			)
			(layer "B.Fab")
		)
		(fp_line
			(start 0.67945 0.3048)
			(end 0.67945 -0.305054)
			(stroke
				(width 0.1)
				(type default)
			)
			(layer "B.Fab")
		)
		(fp_line
			(start 0.12065 0.3048)
			(end 0.67945 0.3048)
			(stroke
				(width 0.1)
				(type default)
			)
			(layer "B.Fab")
		)
		(fp_line
			(start -0.120396 0.3048)
			(end -0.120396 0.2794)
			(stroke
				(width 0.1)
				(type default)
			)
			(layer "B.Fab")
		)
		(fp_line
			(start -0.67945 0.3048)
			(end -0.120396 0.3048)
			(stroke
				(width 0.1)
				(type default)
			)
			(layer "B.Fab")
		)
		(pad "1" smd circle
			(at 0.40005 0 270)
			(size 0 0)
			(layers "B.Cu" "B.Mask" "B.Paste")
			(net "P1V2_AUX")
		)
		(pad "2" smd circle
			(at -0.40005 0 270)
			(size 0 0)
			(layers "B.Cu" "B.Mask" "B.Paste")
			(net "GND")
		)
	)
	(footprint ""
		(layer "B.Cu")
		(at 302.133 -358.14 180)
		(property "Reference" "R8045"
			(at 0 0 0)
			(layer "B.SilkS")
			(hide yes)
			(effects
				(font
					(size 1.27 1.27)
				)
				(justify mirror)
			)
		)
		(property "Value" ""
			(at 0 0 0)
			(layer "B.Fab")
			(effects
				(font
					(size 1.27 1.27)
				)
				(justify mirror)
			)
		)
		(duplicate_pad_numbers_are_jumpers no)
		(fp_line
			(start 0.7874 0.4064)
			(end 0.7874 -0.4064)
			(stroke
				(width 0.1524)
				(type default)
			)
			(layer "B.SilkS")
		)
		(fp_line
			(start 0.7874 -0.4064)
			(end -0.7874 -0.4064)
			(stroke
				(width 0.1524)
				(type default)
			)
			(layer "B.SilkS")
		)
		(fp_line
			(start -0.7874 0.4064)
			(end 0.7874 0.4064)
			(stroke
				(width 0.1524)
				(type default)
			)
			(layer "B.SilkS")
		)
		(fp_line
			(start -0.7874 -0.4064)
			(end -0.7874 0.4064)
			(stroke
				(width 0.1524)
				(type default)
			)
			(layer "B.SilkS")
		)
		(fp_line
			(start 0.67945 0.3048)
			(end 0.67945 -0.305054)
			(stroke
				(width 0.1)
				(type default)
			)
			(layer "B.Fab")
		)
		(fp_line
			(start 0.67945 -0.305054)
			(end 0.12065 -0.305054)
			(stroke
				(width 0.1)
				(type default)
			)
			(layer "B.Fab")
		)
		(fp_line
			(start 0.12065 0.3048)
			(end 0.67945 0.3048)
			(stroke
				(width 0.1)
				(type default)
			)
			(layer "B.Fab")
		)
		(fp_line
			(start 0.12065 0.2794)
			(end 0.12065 0.3048)
			(stroke
				(width 0.1)
				(type default)
			)
			(layer "B.Fab")
		)
		(fp_line
			(start 0.12065 -0.2794)
			(end -0.12065 -0.2794)
			(stroke
				(width 0.1)
				(type default)
			)
			(layer "B.Fab")
		)
		(fp_line
			(start 0.12065 -0.305054)
			(end 0.12065 -0.2794)
			(stroke
				(width 0.1)
				(type default)
			)
			(layer "B.Fab")
		)
		(fp_line
			(start -0.120396 0.3048)
			(end -0.120396 0.2794)
			(stroke
				(width 0.1)
				(type default)
			)
			(layer "B.Fab")
		)
		(fp_line
			(start -0.120396 0.2794)
			(end 0.12065 0.2794)
			(stroke
				(width 0.1)
				(type default)
			)
			(layer "B.Fab")
		)
		(fp_line
			(start -0.12065 -0.2794)
			(end -0.12065 -0.3048)
			(stroke
				(width 0.1)
				(type default)
			)
			(layer "B.Fab")
		)
		(fp_line
			(start -0.12065 -0.3048)
			(end -0.67945 -0.3048)
			(stroke
				(width 0.1)
				(type default)
			)
			(layer "B.Fab")
		)
		(fp_line
			(start -0.67945 0.3048)
			(end -0.120396 0.3048)
			(stroke
				(width 0.1)
				(type default)
			)
			(layer "B.Fab")
		)
		(fp_line
			(start -0.67945 -0.3048)
			(end -0.67945 0.3048)
			(stroke
				(width 0.1)
				(type default)
			)
			(layer "B.Fab")
		)
		(pad "1" smd circle
			(at 0.40005 0)
			(size 0 0)
			(layers "B.Cu" "B.Mask" "B.Paste")
			(net "PVDD18_S5_P0")
		)
		(pad "2" smd circle
			(at -0.40005 0)
			(size 0 0)
			(layers "B.Cu" "B.Mask" "B.Paste")
			(net "SVID_PVDDCR_CPU1_P0_SVD_R")
		)
	)
)
